(kicad_pcb
	(version 20260206)
	(generator "pcbnew")
	(generator_version "10.0")
	(general
		(thickness 1.6)
		(legacy_teardrops no)
	)
	(paper "A4")
	(title_block
		(title "Wiwynn_Tioga_Pass_MB.brd")
		(comment 1 "Tioga Pass / footprints 4276-4280 of 4770")
	)
	(layers
		(0 "F.Cu" signal "TOP")
		(4 "In1.Cu" signal "L2GND")
		(6 "In2.Cu" signal "L3")
		(8 "In3.Cu" signal "L4GND")
		(10 "In4.Cu" signal "L5")
		(12 "In5.Cu" signal "L6GND")
		(14 "In6.Cu" signal "L7VCC")
		(16 "In7.Cu" signal "L8VCC")
		(18 "In8.Cu" signal "L9GND")
		(20 "In9.Cu" signal "L10")
		(22 "In10.Cu" signal "L11GND")
		(24 "In11.Cu" signal "L12")
		(26 "In12.Cu" signal "L13GND")
		(2 "B.Cu" signal "BOTTOM")
		(9 "F.Adhes" user "F.Adhesive")
		(11 "B.Adhes" user "B.Adhesive")
		(13 "F.Paste" user "Package Geometry/Pastemask Top")
		(15 "B.Paste" user "Package Geometry/Pastemask Bottom")
		(5 "F.SilkS" user "Ref Des/Silkscreen Top")
		(7 "B.SilkS" user "Ref Des/Silkscreen Bottom")
		(1 "F.Mask" user "Board Geometry/Soldermask Top")
		(3 "B.Mask" user "Board Geometry/Soldermask Bottom")
		(17 "Dwgs.User" user "User.Drawings")
		(19 "Cmts.User" user "User.Comments")
		(21 "Eco1.User" user "User.Eco1")
		(23 "Eco2.User" user "User.Eco2")
		(25 "Edge.Cuts" user "Board Geometry/Outline")
		(27 "Margin" user)
		(31 "F.CrtYd" user "Package Geometry/Place Bound Top")
		(29 "B.CrtYd" user "Package Geometry/Place Bound Bottom")
		(35 "F.Fab" user "Ref Des/Assembly Top")
		(33 "B.Fab" user "Ref Des/Assembly Bottom")
	)
	(footprint ""
		(layer "B.Cu")
		(at 437.515 -52.3875)
		(property "Reference" "C2R17"
			(at 0 0 0)
			(layer "B.SilkS")
			(hide yes)
			(effects
				(font
					(size 1.27 1.27)
				)
				(justify mirror)
			)
		)
		(property "Value" ""
			(at 0 0 0)
			(layer "B.Fab")
			(effects
				(font
					(size 1.27 1.27)
				)
				(justify mirror)
			)
		)
		(duplicate_pad_numbers_are_jumpers no)
		(fp_poly
			(pts
				(xy -0.3048 -0.1016) (xy -0.3048 0.9906) (xy 0.3048 0.9906) (xy 0.3048 -0.1016)
			)
			(stroke
				(width 0)
				(type default)
			)
			(fill no)
			(layer "B.CrtYd")
		)
		(fp_line
			(start -0.3048 -0.1016)
			(end 0.3048 -0.1016)
			(stroke
				(width 0.1)
				(type default)
			)
			(layer "B.Fab")
		)
		(fp_line
			(start -0.3048 0.9906)
			(end -0.3048 -0.1016)
			(stroke
				(width 0.1)
				(type default)
			)
			(layer "B.Fab")
		)
		(fp_line
			(start 0.3048 -0.1016)
			(end 0.3048 0.9906)
			(stroke
				(width 0.1)
				(type default)
			)
			(layer "B.Fab")
		)
		(fp_line
			(start 0.3048 0.9906)
			(end -0.3048 0.9906)
			(stroke
				(width 0.1)
				(type default)
			)
			(layer "B.Fab")
		)
		(pad "1" smd rect
			(at 0 0 180)
			(size 0.508 0.508)
			(layers "B.Cu" "B.Mask" "B.Paste")
			(net "P12V_STBY")
		)
		(pad "2" smd rect
			(at 0 0.889 180)
			(size 0.508 0.508)
			(layers "B.Cu" "B.Mask" "B.Paste")
			(net "GND")
		)
		(zone
			(layer "B.Cu")
			(hatch none 0.5)
			(connect_pads
				(clearance 0)
			)
			(min_thickness 0.25)
			(keepout
				(tracks allowed)
				(vias not_allowed)
				(pads allowed)
				(copperpour not_allowed)
				(footprints allowed)
			)
			(placement
				(enabled no)
				(sheetname "")
			)
			(fill
				(thermal_gap 0.5)
				(thermal_bridge_width 0.5)
				(island_removal_mode 0)
			)
			(polygon
				(pts
					(xy 437.769 -52.1335) (xy 437.261 -52.1335) (xy 437.261 -51.7525) (xy 437.769 -51.7525)
				)
			)
		)
		(zone
			(layer "B.Cu")
			(hatch none 0.5)
			(connect_pads
				(clearance 0)
			)
			(min_thickness 0.25)
			(keepout
				(tracks not_allowed)
				(vias allowed)
				(pads allowed)
				(copperpour not_allowed)
				(footprints allowed)
			)
			(placement
				(enabled no)
				(sheetname "")
			)
			(fill
				(thermal_gap 0.5)
				(thermal_bridge_width 0.5)
				(island_removal_mode 0)
			)
			(polygon
				(pts
					(xy 437.769 -51.7525) (xy 437.261 -51.7525) (xy 437.261 -52.1335) (xy 437.769 -52.1335)
				)
			)
		)
	)
	(footprint ""
		(layer "B.Cu")
		(at 164.973 -84.709 90)
		(property "Reference" "C6P5"
			(at 0 0 90)
			(layer "B.SilkS")
			(hide yes)
			(effects
				(font
					(size 1.27 1.27)
				)
				(justify mirror)
			)
		)
		(property "Value" ""
			(at 0 0 90)
			(layer "B.Fab")
			(effects
				(font
					(size 1.27 1.27)
				)
				(justify mirror)
			)
		)
		(duplicate_pad_numbers_are_jumpers no)
		(fp_poly
			(pts
				(xy -0.3048 -0.1016) (xy -0.3048 0.9906) (xy 0.3048 0.9906) (xy 0.3048 -0.1016)
			)
			(stroke
				(width 0)
				(type default)
			)
			(fill no)
			(layer "B.CrtYd")
		)
		(fp_line
			(start 0.3048 -0.1016)
			(end 0.3048 0.9906)
			(stroke
				(width 0.1)
				(type default)
			)
			(layer "B.Fab")
		)
		(fp_line
			(start -0.3048 -0.1016)
			(end 0.3048 -0.1016)
			(stroke
				(width 0.1)
				(type default)
			)
			(layer "B.Fab")
		)
		(fp_line
			(start 0.3048 0.9906)
			(end -0.3048 0.9906)
			(stroke
				(width 0.1)
				(type default)
			)
			(layer "B.Fab")
		)
		(fp_line
			(start -0.3048 0.9906)
			(end -0.3048 -0.1016)
			(stroke
				(width 0.1)
				(type default)
			)
			(layer "B.Fab")
		)
		(pad "1" smd rect
			(at 0 0 270)
			(size 0.508 0.508)
			(layers "B.Cu" "B.Mask" "B.Paste")
			(net "P3V3_DB1200")
		)
		(pad "2" smd rect
			(at 0 0.889 270)
			(size 0.508 0.508)
			(layers "B.Cu" "B.Mask" "B.Paste")
			(net "GND")
		)
		(zone
			(layer "B.Cu")
			(hatch none 0.5)
			(connect_pads
				(clearance 0)
			)
			(min_thickness 0.25)
			(keepout
				(tracks allowed)
				(vias not_allowed)
				(pads allowed)
				(copperpour not_allowed)
				(footprints allowed)
			)
			(placement
				(enabled no)
				(sheetname "")
			)
			(fill
				(thermal_gap 0.5)
				(thermal_bridge_width 0.5)
				(island_removal_mode 0)
			)
			(polygon
				(pts
					(xy 165.227 -84.963) (xy 165.227 -84.455) (xy 165.608 -84.455) (xy 165.608 -84.963)
				)
			)
		)
		(zone
			(layer "B.Cu")
			(hatch none 0.5)
			(connect_pads
				(clearance 0)
			)
			(min_thickness 0.25)
			(keepout
				(tracks not_allowed)
				(vias allowed)
				(pads allowed)
				(copperpour not_allowed)
				(footprints allowed)
			)
			(placement
				(enabled no)
				(sheetname "")
			)
			(fill
				(thermal_gap 0.5)
				(thermal_bridge_width 0.5)
				(island_removal_mode 0)
			)
			(polygon
				(pts
					(xy 165.608 -84.963) (xy 165.608 -84.455) (xy 165.227 -84.455) (xy 165.227 -84.963)
				)
			)
		)
	)
	(footprint ""
		(layer "B.Cu")
		(at 448.55638 -34.7345 90)
		(property "Reference" "R25W48"
			(at 0 0 90)
			(layer "B.SilkS")
			(hide yes)
			(effects
				(font
					(size 1.27 1.27)
				)
				(justify mirror)
			)
		)
		(property "Value" "*"
			(at -0.064008 -4.108196 90)
			(unlocked yes)
			(layer "B.Fab")
			(hide yes)
			(effects
				(font
					(size 1.27 1.016)
					(thickness 0.1524)
				)
				(justify mirror)
			)
		)
		(property "Device Type" "120R2F-GP_RCL_GP-120R2F-GP,64.A"
			(at -0.064008 -5.632196 90)
			(unlocked yes)
			(layer "B.Fab")
			(hide yes)
			(effects
				(font
					(size 1.27 1.016)
					(thickness 0.1524)
				)
				(justify mirror)
			)
		)
		(duplicate_pad_numbers_are_jumpers no)
		(fp_line
			(start 0.508 -0.9398)
			(end 0.508 0.9398)
			(stroke
				(width 0.1524)
				(type default)
			)
			(layer "B.SilkS")
		)
		(fp_line
			(start -0.508 -0.9398)
			(end 0.508 -0.9398)
			(stroke
				(width 0.1524)
				(type default)
			)
			(layer "B.SilkS")
		)
		(fp_rect
			(start 0.508 0.9398)
			(end -0.508 -0.9398)
			(stroke
				(width 0)
				(type default)
			)
			(fill no)
			(layer "B.CrtYd")
		)
		(fp_rect
			(start 0.508 0.9398)
			(end -0.508 -0.9398)
			(stroke
				(width 0)
				(type default)
			)
			(fill no)
			(layer "B.Fab")
		)
		(pad "1" smd custom
			(at 0 -0.4445 270)
			(size 0.1397 0.1397)
			(layers "B.Cu" "B.Mask" "B.Paste")
			(net "BMC_M_A10")
			(options
				(clearance outline)
				(anchor circle)
			)
			(primitives
				(gr_poly
					(pts
						(arc
							(start -0.1778 0.2794)
							(mid -0.249642 0.249642)
							(end -0.2794 0.1778)
						)
						(arc
							(start -0.2794 -0.1778)
							(mid -0.249642 -0.249642)
							(end -0.1778 -0.2794)
						)
						(arc
							(start 0.1778 -0.2794)
							(mid 0.249642 -0.249642)
							(end 0.2794 -0.1778)
						)
						(arc
							(start 0.2794 0.1778)
							(mid 0.249642 0.249642)
							(end 0.1778 0.2794)
						)
					)
					(width 0)
					(fill yes)
				)
			)
		)
		(pad "2" smd custom
			(at 0 0.4445 270)
			(size 0.1397 0.1397)
			(layers "B.Cu" "B.Mask" "B.Paste")
			(net "P1V2_AUX_BMC")
			(options
				(clearance outline)
				(anchor circle)
			)
			(primitives
				(gr_poly
					(pts
						(arc
							(start -0.1778 0.2794)
							(mid -0.249642 0.249642)
							(end -0.2794 0.1778)
						)
						(arc
							(start -0.2794 -0.1778)
							(mid -0.249642 -0.249642)
							(end -0.1778 -0.2794)
						)
						(arc
							(start 0.1778 -0.2794)
							(mid 0.249642 -0.249642)
							(end 0.2794 -0.1778)
						)
						(arc
							(start 0.2794 0.1778)
							(mid 0.249642 0.249642)
							(end 0.1778 0.2794)
						)
					)
					(width 0)
					(fill yes)
				)
			)
		)
	)
	(footprint ""
		(layer "B.Cu")
		(at 280.354024 -77.366114)
		(property "Reference" "C4P6"
			(at 0 0 0)
			(layer "B.SilkS")
			(hide yes)
			(effects
				(font
					(size 1.27 1.27)
				)
				(justify mirror)
			)
		)
		(property "Value" ""
			(at 0 0 0)
			(layer "B.Fab")
			(effects
				(font
					(size 1.27 1.27)
				)
				(justify mirror)
			)
		)
		(duplicate_pad_numbers_are_jumpers no)
		(fp_poly
			(pts
				(xy 0.4953 -0.2032) (xy -0.4953 -0.2032) (xy -0.4953 1.6002) (xy 0.4953 1.6002)
			)
			(stroke
				(width 0)
				(type default)
			)
			(fill no)
			(layer "B.CrtYd")
		)
		(fp_line
			(start -0.4953 -0.2032)
			(end -0.4953 1.6002)
			(stroke
				(width 0.1)
				(type default)
			)
			(layer "B.Fab")
		)
		(fp_line
			(start -0.4953 1.6002)
			(end 0.4953 1.6002)
			(stroke
				(width 0.1)
				(type default)
			)
			(layer "B.Fab")
		)
		(fp_line
			(start 0.4953 -0.2032)
			(end -0.4953 -0.2032)
			(stroke
				(width 0.1)
				(type default)
			)
			(layer "B.Fab")
		)
		(fp_line
			(start 0.4953 1.6002)
			(end 0.4953 -0.2032)
			(stroke
				(width 0.1)
				(type default)
			)
			(layer "B.Fab")
		)
		(pad "1" smd rect
			(at 0 0 180)
			(size 0.762 0.889)
			(layers "B.Cu" "B.Mask" "B.Paste")
			(net "PVCCIO_CPU0")
		)
		(pad "2" smd rect
			(at 0 1.397 180)
			(size 0.762 0.889)
			(layers "B.Cu" "B.Mask" "B.Paste")
			(net "GND")
		)
		(zone
			(layer "B.Cu")
			(hatch none 0.5)
			(connect_pads
				(clearance 0)
			)
			(min_thickness 0.25)
			(keepout
				(tracks not_allowed)
				(vias allowed)
				(pads allowed)
				(copperpour not_allowed)
				(footprints allowed)
			)
			(placement
				(enabled no)
				(sheetname "")
			)
			(fill
				(thermal_gap 0.5)
				(thermal_bridge_width 0.5)
				(island_removal_mode 0)
			)
			(polygon
				(pts
					(xy 280.735024 -76.921614) (xy 279.973024 -76.921614) (xy 279.973024 -76.413614) (xy 280.735024 -76.413614)
				)
			)
		)
	)
	(footprint ""
		(layer "B.Cu")
		(at 429.7172 -23.4188)
		(property "Reference" "R1U18"
			(at 0 0 0)
			(layer "B.SilkS")
			(hide yes)
			(effects
				(font
					(size 1.27 1.27)
				)
				(justify mirror)
			)
		)
		(property "Value" ""
			(at 0 0 0)
			(layer "B.Fab")
			(effects
				(font
					(size 1.27 1.27)
				)
				(justify mirror)
			)
		)
		(duplicate_pad_numbers_are_jumpers no)
		(fp_poly
			(pts
				(xy 0.2794 -0.1016) (xy -0.2794 -0.1016) (xy -0.2794 0.9906) (xy 0.2794 0.9906)
			)
			(stroke
				(width 0)
				(type default)
			)
			(fill no)
			(layer "B.CrtYd")
		)
		(fp_line
			(start -0.2794 -0.1016)
			(end 0.2794 -0.1016)
			(stroke
				(width 0.1)
				(type default)
			)
			(layer "B.Fab")
		)
		(fp_line
			(start -0.2794 0.9906)
			(end -0.2794 -0.1016)
			(stroke
				(width 0.1)
				(type default)
			)
			(layer "B.Fab")
		)
		(fp_line
			(start 0.2794 -0.1016)
			(end 0.2794 0.9906)
			(stroke
				(width 0.1)
				(type default)
			)
			(layer "B.Fab")
		)
		(fp_line
			(start 0.2794 0.9906)
			(end -0.2794 0.9906)
			(stroke
				(width 0.1)
				(type default)
			)
			(layer "B.Fab")
		)
		(pad "1" smd rect
			(at 0 0 180)
			(size 0.508 0.508)
			(layers "B.Cu" "B.Mask" "B.Paste")
			(net "FM_BOARD_SKU_ID0")
		)
		(pad "2" smd rect
			(at 0 0.889 180)
			(size 0.508 0.508)
			(layers "B.Cu" "B.Mask" "B.Paste")
			(net "GND")
		)
		(zone
			(layer "B.Cu")
			(hatch none 0.5)
			(connect_pads
				(clearance 0)
			)
			(min_thickness 0.25)
			(keepout
				(tracks allowed)
				(vias not_allowed)
				(pads allowed)
				(copperpour not_allowed)
				(footprints allowed)
			)
			(placement
				(enabled no)
				(sheetname "")
			)
			(fill
				(thermal_gap 0.5)
				(thermal_bridge_width 0.5)
				(island_removal_mode 0)
			)
			(polygon
				(pts
					(xy 429.9712 -23.1648) (xy 429.4632 -23.1648) (xy 429.4632 -22.7838) (xy 429.9712 -22.7838)
				)
			)
		)
		(zone
			(layer "B.Cu")
			(hatch none 0.5)
			(connect_pads
				(clearance 0)
			)
			(min_thickness 0.25)
			(keepout
				(tracks not_allowed)
				(vias allowed)
				(pads allowed)
				(copperpour not_allowed)
				(footprints allowed)
			)
			(placement
				(enabled no)
				(sheetname "")
			)
			(fill
				(thermal_gap 0.5)
				(thermal_bridge_width 0.5)
				(island_removal_mode 0)
			)
			(polygon
				(pts
					(xy 429.9712 -22.7838) (xy 429.4632 -22.7838) (xy 429.4632 -23.1648) (xy 429.9712 -23.1648)
				)
			)
		)
	)
)
